(kicad_pcb
	(version 20260206)
	(generator "pcbnew")
	(generator_version "10.0")
	(general
		(thickness 1.6)
		(legacy_teardrops no)
	)
	(paper "A4")
	(title_block
		(title "03242023_DA0F0TMBIJ0_F0T_Motherboard_J_brd_V01_OCP.brd")
		(comment 1 "Grand Teton / footprints 6031-6037 of 6105")
	)
	(layers
		(0 "F.Cu" signal "TOP")
		(4 "In1.Cu" signal "GND")
		(6 "In2.Cu" signal "IN1")
		(8 "In3.Cu" signal "GND1")
		(10 "In4.Cu" signal "IN2")
		(12 "In5.Cu" signal "GND2")
		(14 "In6.Cu" signal "IN3")
		(16 "In7.Cu" signal "GND3")
		(18 "In8.Cu" signal "VCC")
		(20 "In9.Cu" signal "VCC1")
		(22 "In10.Cu" signal "GND4")
		(24 "In11.Cu" signal "IN4")
		(26 "In12.Cu" signal "GND5")
		(28 "In13.Cu" signal "IN5")
		(30 "In14.Cu" signal "GND6")
		(32 "In15.Cu" signal "IN6")
		(34 "In16.Cu" signal "GND7")
		(2 "B.Cu" signal "BOTTOM")
		(9 "F.Adhes" user "F.Adhesive")
		(11 "B.Adhes" user "B.Adhesive")
		(13 "F.Paste" user "Package Geometry/Pastemask Top")
		(15 "B.Paste" user "Package Geometry/Pastemask Bottom")
		(5 "F.SilkS" user "Ref Des/Silkscreen Top")
		(7 "B.SilkS" user "Ref Des/Silkscreen Bottom")
		(1 "F.Mask" user "Board Geometry/Soldermask Top")
		(3 "B.Mask" user "Board Geometry/Soldermask Bottom")
		(17 "Dwgs.User" user "User.Drawings")
		(19 "Cmts.User" user "User.Comments")
		(21 "Eco1.User" user "User.Eco1")
		(23 "Eco2.User" user "User.Eco2")
		(25 "Edge.Cuts" user "Board Geometry/Outline")
		(27 "Margin" user)
		(31 "F.CrtYd" user "Package Geometry/Place Bound Top")
		(29 "B.CrtYd" user "Package Geometry/Place Bound Bottom")
		(35 "F.Fab" user "Ref Des/Assembly Top")
		(33 "B.Fab" user "Ref Des/Assembly Bottom")
	)
	(footprint ""
		(layer "B.Cu")
		(at 364.342934 -248.498106 -90)
		(property "Reference" "C373"
			(at 0 0 90)
			(layer "B.SilkS")
			(hide yes)
			(effects
				(font
					(size 1.27 1.27)
				)
				(justify mirror)
			)
		)
		(property "Value" ""
			(at 0 0 90)
			(layer "B.Fab")
			(effects
				(font
					(size 1.27 1.27)
				)
				(justify mirror)
			)
		)
		(duplicate_pad_numbers_are_jumpers no)
		(fp_line
			(start -1.524 0.762)
			(end 1.524 0.762)
			(stroke
				(width 0.1524)
				(type default)
			)
			(layer "B.SilkS")
		)
		(fp_line
			(start 1.524 0.762)
			(end 1.524 -0.762)
			(stroke
				(width 0.1524)
				(type default)
			)
			(layer "B.SilkS")
		)
		(fp_line
			(start -1.524 -0.762)
			(end -1.524 0.762)
			(stroke
				(width 0.1524)
				(type default)
			)
			(layer "B.SilkS")
		)
		(fp_line
			(start 1.524 -0.762)
			(end -1.524 -0.762)
			(stroke
				(width 0.1524)
				(type default)
			)
			(layer "B.SilkS")
		)
		(fp_line
			(start -1.1049 0.724916)
			(end -1.1049 -0.724916)
			(stroke
				(width 0.1)
				(type default)
			)
			(layer "B.Fab")
		)
		(fp_line
			(start 1.1049 0.724916)
			(end -1.1049 0.724916)
			(stroke
				(width 0.1)
				(type default)
			)
			(layer "B.Fab")
		)
		(fp_line
			(start -1.1049 -0.724916)
			(end 1.1049 -0.724916)
			(stroke
				(width 0.1)
				(type default)
			)
			(layer "B.Fab")
		)
		(fp_line
			(start 1.1049 -0.724916)
			(end 1.1049 0.724916)
			(stroke
				(width 0.1)
				(type default)
			)
			(layer "B.Fab")
		)
		(pad "1" smd rect
			(at 0.889 0 270)
			(size 1.016 1.27)
			(layers "B.Cu" "B.Mask" "B.Paste")
			(net "PVCCIN_CPU0")
		)
		(pad "2" smd rect
			(at -0.889 0 270)
			(size 1.016 1.27)
			(layers "B.Cu" "B.Mask" "B.Paste")
			(net "GND")
		)
	)
	(footprint ""
		(layer "B.Cu")
		(at 185.142886 -193.599816 -90)
		(property "Reference" "R822"
			(at 0 0 90)
			(layer "B.SilkS")
			(hide yes)
			(effects
				(font
					(size 1.27 1.27)
				)
				(justify mirror)
			)
		)
		(property "Value" ""
			(at 0 0 90)
			(layer "B.Fab")
			(effects
				(font
					(size 1.27 1.27)
				)
				(justify mirror)
			)
		)
		(duplicate_pad_numbers_are_jumpers no)
		(fp_line
			(start -0.7874 0.4064)
			(end 0.7874 0.4064)
			(stroke
				(width 0.1524)
				(type default)
			)
			(layer "B.SilkS")
		)
		(fp_line
			(start 0.7874 0.4064)
			(end 0.7874 -0.4064)
			(stroke
				(width 0.1524)
				(type default)
			)
			(layer "B.SilkS")
		)
		(fp_line
			(start -0.7874 -0.4064)
			(end -0.7874 0.4064)
			(stroke
				(width 0.1524)
				(type default)
			)
			(layer "B.SilkS")
		)
		(fp_line
			(start 0.7874 -0.4064)
			(end -0.7874 -0.4064)
			(stroke
				(width 0.1524)
				(type default)
			)
			(layer "B.SilkS")
		)
		(fp_line
			(start -0.67945 0.3048)
			(end -0.120396 0.3048)
			(stroke
				(width 0.1)
				(type default)
			)
			(layer "B.Fab")
		)
		(fp_line
			(start -0.120396 0.3048)
			(end -0.120396 0.2794)
			(stroke
				(width 0.1)
				(type default)
			)
			(layer "B.Fab")
		)
		(fp_line
			(start 0.12065 0.3048)
			(end 0.67945 0.3048)
			(stroke
				(width 0.1)
				(type default)
			)
			(layer "B.Fab")
		)
		(fp_line
			(start 0.67945 0.3048)
			(end 0.67945 -0.305054)
			(stroke
				(width 0.1)
				(type default)
			)
			(layer "B.Fab")
		)
		(fp_line
			(start -0.120396 0.2794)
			(end 0.12065 0.2794)
			(stroke
				(width 0.1)
				(type default)
			)
			(layer "B.Fab")
		)
		(fp_line
			(start 0.12065 0.2794)
			(end 0.12065 0.3048)
			(stroke
				(width 0.1)
				(type default)
			)
			(layer "B.Fab")
		)
		(fp_line
			(start -0.12065 -0.2794)
			(end -0.12065 -0.3048)
			(stroke
				(width 0.1)
				(type default)
			)
			(layer "B.Fab")
		)
		(fp_line
			(start 0.12065 -0.2794)
			(end -0.12065 -0.2794)
			(stroke
				(width 0.1)
				(type default)
			)
			(layer "B.Fab")
		)
		(fp_line
			(start -0.67945 -0.3048)
			(end -0.67945 0.3048)
			(stroke
				(width 0.1)
				(type default)
			)
			(layer "B.Fab")
		)
		(fp_line
			(start -0.12065 -0.3048)
			(end -0.67945 -0.3048)
			(stroke
				(width 0.1)
				(type default)
			)
			(layer "B.Fab")
		)
		(fp_line
			(start 0.12065 -0.305054)
			(end 0.12065 -0.2794)
			(stroke
				(width 0.1)
				(type default)
			)
			(layer "B.Fab")
		)
		(fp_line
			(start 0.67945 -0.305054)
			(end 0.12065 -0.305054)
			(stroke
				(width 0.1)
				(type default)
			)
			(layer "B.Fab")
		)
		(pad "1" smd circle
			(at 0.40005 0 90)
			(size 0 0)
			(layers "B.Cu" "B.Mask" "B.Paste")
			(net "PVCCD_HV_CPU1")
		)
		(pad "2" smd circle
			(at -0.40005 0 90)
			(size 0 0)
			(layers "B.Cu" "B.Mask" "B.Paste")
			(net "RST_M_EF_CPU1_FPGA_N")
		)
	)
	(footprint ""
		(layer "B.Cu")
		(at 17.75206 -193.843656 180)
		(property "Reference" "C560"
			(at 0 0 0)
			(layer "B.SilkS")
			(hide yes)
			(effects
				(font
					(size 1.27 1.27)
				)
				(justify mirror)
			)
		)
		(property "Value" ""
			(at 0 0 0)
			(layer "B.Fab")
			(effects
				(font
					(size 1.27 1.27)
				)
				(justify mirror)
			)
		)
		(duplicate_pad_numbers_are_jumpers no)
		(fp_line
			(start 0.7874 0.4064)
			(end 0.7874 -0.4064)
			(stroke
				(width 0.1524)
				(type default)
			)
			(layer "B.SilkS")
		)
		(fp_line
			(start 0.7874 -0.4064)
			(end -0.7874 -0.4064)
			(stroke
				(width 0.1524)
				(type default)
			)
			(layer "B.SilkS")
		)
		(fp_line
			(start -0.7874 0.4064)
			(end 0.7874 0.4064)
			(stroke
				(width 0.1524)
				(type default)
			)
			(layer "B.SilkS")
		)
		(fp_line
			(start -0.7874 -0.4064)
			(end -0.7874 0.4064)
			(stroke
				(width 0.1524)
				(type default)
			)
			(layer "B.SilkS")
		)
		(fp_line
			(start 0.67945 0.3048)
			(end 0.67945 -0.305054)
			(stroke
				(width 0.1)
				(type default)
			)
			(layer "B.Fab")
		)
		(fp_line
			(start 0.67945 -0.305054)
			(end 0.12065 -0.305054)
			(stroke
				(width 0.1)
				(type default)
			)
			(layer "B.Fab")
		)
		(fp_line
			(start 0.12065 0.3048)
			(end 0.67945 0.3048)
			(stroke
				(width 0.1)
				(type default)
			)
			(layer "B.Fab")
		)
		(fp_line
			(start 0.12065 0.2794)
			(end 0.12065 0.3048)
			(stroke
				(width 0.1)
				(type default)
			)
			(layer "B.Fab")
		)
		(fp_line
			(start 0.12065 -0.2794)
			(end -0.12065 -0.2794)
			(stroke
				(width 0.1)
				(type default)
			)
			(layer "B.Fab")
		)
		(fp_line
			(start 0.12065 -0.305054)
			(end 0.12065 -0.2794)
			(stroke
				(width 0.1)
				(type default)
			)
			(layer "B.Fab")
		)
		(fp_line
			(start -0.120396 0.3048)
			(end -0.120396 0.2794)
			(stroke
				(width 0.1)
				(type default)
			)
			(layer "B.Fab")
		)
		(fp_line
			(start -0.120396 0.2794)
			(end 0.12065 0.2794)
			(stroke
				(width 0.1)
				(type default)
			)
			(layer "B.Fab")
		)
		(fp_line
			(start -0.12065 -0.2794)
			(end -0.12065 -0.3048)
			(stroke
				(width 0.1)
				(type default)
			)
			(layer "B.Fab")
		)
		(fp_line
			(start -0.12065 -0.3048)
			(end -0.67945 -0.3048)
			(stroke
				(width 0.1)
				(type default)
			)
			(layer "B.Fab")
		)
		(fp_line
			(start -0.67945 0.3048)
			(end -0.120396 0.3048)
			(stroke
				(width 0.1)
				(type default)
			)
			(layer "B.Fab")
		)
		(fp_line
			(start -0.67945 -0.3048)
			(end -0.67945 0.3048)
			(stroke
				(width 0.1)
				(type default)
			)
			(layer "B.Fab")
		)
		(pad "1" smd circle
			(at 0.40005 0)
			(size 0 0)
			(layers "B.Cu" "B.Mask" "B.Paste")
			(net "PVNN_TERM_CPU1")
		)
		(pad "2" smd circle
			(at -0.40005 0)
			(size 0 0)
			(layers "B.Cu" "B.Mask" "B.Paste")
			(net "GND")
		)
	)
	(footprint ""
		(layer "B.Cu")
		(at 349.675704 -64.18072)
		(property "Reference" "C156"
			(at 0 0 0)
			(layer "B.SilkS")
			(hide yes)
			(effects
				(font
					(size 1.27 1.27)
				)
				(justify mirror)
			)
		)
		(property "Value" ""
			(at 0 0 0)
			(layer "B.Fab")
			(effects
				(font
					(size 1.27 1.27)
				)
				(justify mirror)
			)
		)
		(duplicate_pad_numbers_are_jumpers no)
		(fp_line
			(start -0.299974 -0.150114)
			(end -0.299974 0.150114)
			(stroke
				(width 0.1)
				(type default)
			)
			(layer "B.Fab")
		)
		(fp_line
			(start -0.299974 0.150114)
			(end 0.299974 0.150114)
			(stroke
				(width 0.1)
				(type default)
			)
			(layer "B.Fab")
		)
		(fp_line
			(start 0.299974 -0.150114)
			(end -0.299974 -0.150114)
			(stroke
				(width 0.1)
				(type default)
			)
			(layer "B.Fab")
		)
		(fp_line
			(start 0.299974 0.150114)
			(end 0.299974 -0.150114)
			(stroke
				(width 0.1)
				(type default)
			)
			(layer "B.Fab")
		)
		(pad "1" smd rect
			(at 0.2667 0 180)
			(size 0.3048 0.381)
			(layers "B.Cu" "B.Mask" "B.Paste")
			(net "DMI_CPU0_PCH_RX_C_DP<7>")
		)
		(pad "2" smd rect
			(at -0.2667 0 180)
			(size 0.3048 0.381)
			(layers "B.Cu" "B.Mask" "B.Paste")
			(net "DMI_CPU0_PCH_RX_DP<7>")
		)
	)
	(footprint ""
		(layer "B.Cu")
		(at 158.697168 -318.336422)
		(property "Reference" "R3900"
			(at 0 0 0)
			(layer "B.SilkS")
			(hide yes)
			(effects
				(font
					(size 1.27 1.27)
				)
				(justify mirror)
			)
		)
		(property "Value" ""
			(at 0 0 0)
			(layer "B.Fab")
			(effects
				(font
					(size 1.27 1.27)
				)
				(justify mirror)
			)
		)
		(duplicate_pad_numbers_are_jumpers no)
		(fp_line
			(start -0.7874 -0.4064)
			(end -0.7874 0.4064)
			(stroke
				(width 0.1524)
				(type default)
			)
			(layer "B.SilkS")
		)
		(fp_line
			(start -0.7874 0.4064)
			(end 0.7874 0.4064)
			(stroke
				(width 0.1524)
				(type default)
			)
			(layer "B.SilkS")
		)
		(fp_line
			(start 0.7874 -0.4064)
			(end -0.7874 -0.4064)
			(stroke
				(width 0.1524)
				(type default)
			)
			(layer "B.SilkS")
		)
		(fp_line
			(start 0.7874 0.4064)
			(end 0.7874 -0.4064)
			(stroke
				(width 0.1524)
				(type default)
			)
			(layer "B.SilkS")
		)
		(fp_line
			(start -0.67945 -0.3048)
			(end -0.67945 0.3048)
			(stroke
				(width 0.1)
				(type default)
			)
			(layer "B.Fab")
		)
		(fp_line
			(start -0.67945 0.3048)
			(end -0.120396 0.3048)
			(stroke
				(width 0.1)
				(type default)
			)
			(layer "B.Fab")
		)
		(fp_line
			(start -0.12065 -0.3048)
			(end -0.67945 -0.3048)
			(stroke
				(width 0.1)
				(type default)
			)
			(layer "B.Fab")
		)
		(fp_line
			(start -0.12065 -0.2794)
			(end -0.12065 -0.3048)
			(stroke
				(width 0.1)
				(type default)
			)
			(layer "B.Fab")
		)
		(fp_line
			(start -0.120396 0.2794)
			(end 0.12065 0.2794)
			(stroke
				(width 0.1)
				(type default)
			)
			(layer "B.Fab")
		)
		(fp_line
			(start -0.120396 0.3048)
			(end -0.120396 0.2794)
			(stroke
				(width 0.1)
				(type default)
			)
			(layer "B.Fab")
		)
		(fp_line
			(start 0.12065 -0.305054)
			(end 0.12065 -0.2794)
			(stroke
				(width 0.1)
				(type default)
			)
			(layer "B.Fab")
		)
		(fp_line
			(start 0.12065 -0.2794)
			(end -0.12065 -0.2794)
			(stroke
				(width 0.1)
				(type default)
			)
			(layer "B.Fab")
		)
		(fp_line
			(start 0.12065 0.2794)
			(end 0.12065 0.3048)
			(stroke
				(width 0.1)
				(type default)
			)
			(layer "B.Fab")
		)
		(fp_line
			(start 0.12065 0.3048)
			(end 0.67945 0.3048)
			(stroke
				(width 0.1)
				(type default)
			)
			(layer "B.Fab")
		)
		(fp_line
			(start 0.67945 -0.305054)
			(end 0.12065 -0.305054)
			(stroke
				(width 0.1)
				(type default)
			)
			(layer "B.Fab")
		)
		(fp_line
			(start 0.67945 0.3048)
			(end 0.67945 -0.305054)
			(stroke
				(width 0.1)
				(type default)
			)
			(layer "B.Fab")
		)
		(pad "1" smd circle
			(at 0.40005 0 180)
			(size 0 0)
			(layers "B.Cu" "B.Mask" "B.Paste")
			(net "I3C_SPD_DDREFGH_CPU1_LVC1_SCL_1")
		)
		(pad "2" smd circle
			(at -0.40005 0 180)
			(size 0 0)
			(layers "B.Cu" "B.Mask" "B.Paste")
			(net "I3C_SPD_DDREFGH_CPU1_LVC1_SCL")
		)
	)
	(footprint ""
		(layer "B.Cu")
		(at 485.20985 -148.045932 -90)
		(property "Reference" "X18"
			(at 3.762248 3.089656 270)
			(unlocked yes)
			(layer "B.SilkS")
			(effects
				(font
					(size 0.7874 0.5842)
					(thickness 0.1524)
				)
				(justify left mirror)
			)
		)
		(property "Value" ""
			(at 0 0 90)
			(layer "B.Fab")
			(effects
				(font
					(size 1.27 1.27)
				)
				(justify mirror)
			)
		)
		(property "Device Type" "TP_TDR_4P_FTS_MPKT4_H025P0200_I"
			(at -1.30175 1.27 180)
			(unlocked yes)
			(layer "B.Fab")
			(hide yes)
			(effects
				(font
					(size 0.635 0.4064)
					(thickness 0.1524)
				)
				(justify mirror)
			)
		)
		(property "User Part Number" "TP15"
			(at -1.30175 1.27 180)
			(unlocked yes)
			(layer "Cmts.User")
			(hide yes)
			(effects
				(font
					(size 0.635 0.4064)
					(thickness 0.1524)
				)
				(justify mirror)
			)
		)
		(duplicate_pad_numbers_are_jumpers no)
		(fp_line
			(start -2.54 3.81)
			(end -2.54 3.6703)
			(stroke
				(width 0.1524)
				(type default)
			)
			(layer "B.SilkS")
		)
		(fp_line
			(start 0 3.81)
			(end -2.54 3.81)
			(stroke
				(width 0.1524)
				(type default)
			)
			(layer "B.SilkS")
		)
		(fp_line
			(start 0 3.175)
			(end 0 3.81)
			(stroke
				(width 0.1524)
				(type default)
			)
			(layer "B.SilkS")
		)
		(fp_line
			(start -2.54 1.4097)
			(end -2.54 1.1303)
			(stroke
				(width 0.1524)
				(type default)
			)
			(layer "B.SilkS")
		)
		(fp_line
			(start 0 0.635)
			(end 0 1.905)
			(stroke
				(width 0.1524)
				(type default)
			)
			(layer "B.SilkS")
		)
		(fp_line
			(start -2.54 -1.1303)
			(end -2.54 -1.27)
			(stroke
				(width 0.1524)
				(type default)
			)
			(layer "B.SilkS")
		)
		(fp_line
			(start -2.54 -1.27)
			(end 0 -1.27)
			(stroke
				(width 0.1524)
				(type default)
			)
			(layer "B.SilkS")
		)
		(fp_line
			(start 0 -1.27)
			(end 0 -0.635)
			(stroke
				(width 0.1524)
				(type default)
			)
			(layer "B.SilkS")
		)
		(fp_poly
			(pts
				(xy 2.958846 -0.84582) (xy 2.958846 0.67818) (xy 1.434846 -0.08382)
			)
			(stroke
				(width 0)
				(type default)
			)
			(fill yes)
			(layer "B.SilkS")
		)
		(fp_line
			(start -2.54 3.81)
			(end -2.54 -1.27)
			(stroke
				(width 0.1)
				(type default)
			)
			(layer "B.Fab")
		)
		(fp_line
			(start 0 3.81)
			(end -2.54 3.81)
			(stroke
				(width 0.1)
				(type default)
			)
			(layer "B.Fab")
		)
		(fp_line
			(start -2.54 -1.27)
			(end 0 -1.27)
			(stroke
				(width 0.1)
				(type default)
			)
			(layer "B.Fab")
		)
		(fp_line
			(start 0 -1.27)
			(end 0 3.81)
			(stroke
				(width 0.1)
				(type default)
			)
			(layer "B.Fab")
		)
		(fp_poly
			(pts
				(xy 0.761746 0) (xy 2.285746 -0.762) (xy 2.285746 0.762)
			)
			(stroke
				(width 0)
				(type default)
			)
			(fill yes)
			(layer "B.Fab")
		)
		(pad "1" thru_hole circle
			(at 0 0 90)
			(size 1.0033 1.0033)
			(drill 0.249936)
			(layers "*.Cu" "*.Mask")
			(remove_unused_layers no)
			(net "TDR_DIFF_100_BOT_DP")
			(clearance 0.10795)
			(padstack
				(mode front_inner_back)
				(layer "Inner"
					(shape circle)
					(size 0.8001 0.8001)
					(clearance 0.1524)
				)
				(layer "B.Cu"
					(shape circle)
					(size 1.0033 1.0033)
					(thermal_gap 0.10795)
					(clearance 0.10795)
				)
			)
		)
		(pad "2" thru_hole circle
			(at -2.54 0 90)
			(size 1.9939 1.9939)
			(drill 0.249936)
			(layers "*.Cu" "*.Mask")
			(remove_unused_layers no)
			(net "T1_GND")
			(clearance 0.10795)
			(padstack
				(mode front_inner_back)
				(layer "Inner"
					(shape circle)
					(size 0.8001 0.8001)
					(clearance 0.1524)
				)
				(layer "B.Cu"
					(shape circle)
					(size 1.9939 1.9939)
					(thermal_gap 0.10795)
					(clearance 0.10795)
				)
			)
		)
		(pad "3" thru_hole circle
			(at -2.54 2.54 90)
			(size 1.9939 1.9939)
			(drill 0.249936)
			(layers "*.Cu" "*.Mask")
			(remove_unused_layers no)
			(net "T1_GND")
			(clearance 0.10795)
			(padstack
				(mode front_inner_back)
				(layer "Inner"
					(shape circle)
					(size 0.8001 0.8001)
					(clearance 0.1524)
				)
				(layer "B.Cu"
					(shape circle)
					(size 1.9939 1.9939)
					(thermal_gap 0.10795)
					(clearance 0.10795)
				)
			)
		)
		(pad "4" thru_hole circle
			(at 0 2.54 90)
			(size 1.0033 1.0033)
			(drill 0.249936)
			(layers "*.Cu" "*.Mask")
			(remove_unused_layers no)
			(net "TDR_DIFF_100_BOT_DN")
			(clearance 0.10795)
			(padstack
				(mode front_inner_back)
				(layer "Inner"
					(shape circle)
					(size 0.8001 0.8001)
					(clearance 0.1524)
				)
				(layer "B.Cu"
					(shape circle)
					(size 1.0033 1.0033)
					(thermal_gap 0.10795)
					(clearance 0.10795)
				)
			)
		)
	)
	(footprint ""
		(layer "B.Cu")
		(at 138.152378 -333.6163 -90)
		(property "Reference" "PC499_P1_8"
			(at 0 0 90)
			(layer "B.SilkS")
			(hide yes)
			(effects
				(font
					(size 1.27 1.27)
				)
				(justify mirror)
			)
		)
		(property "Value" ""
			(at 0 0 90)
			(layer "B.Fab")
			(effects
				(font
					(size 1.27 1.27)
				)
				(justify mirror)
			)
		)
		(duplicate_pad_numbers_are_jumpers no)
		(fp_line
			(start -1.524 0.762)
			(end 1.524 0.762)
			(stroke
				(width 0.1524)
				(type default)
			)
			(layer "B.SilkS")
		)
		(fp_line
			(start 1.524 0.762)
			(end 1.524 -0.762)
			(stroke
				(width 0.1524)
				(type default)
			)
			(layer "B.SilkS")
		)
		(fp_line
			(start -1.524 -0.762)
			(end -1.524 0.762)
			(stroke
				(width 0.1524)
				(type default)
			)
			(layer "B.SilkS")
		)
		(fp_line
			(start 1.524 -0.762)
			(end -1.524 -0.762)
			(stroke
				(width 0.1524)
				(type default)
			)
			(layer "B.SilkS")
		)
		(fp_line
			(start -1.1049 0.724916)
			(end -1.1049 -0.724916)
			(stroke
				(width 0.1)
				(type default)
			)
			(layer "B.Fab")
		)
		(fp_line
			(start 1.1049 0.724916)
			(end -1.1049 0.724916)
			(stroke
				(width 0.1)
				(type default)
			)
			(layer "B.Fab")
		)
		(fp_line
			(start -1.1049 -0.724916)
			(end 1.1049 -0.724916)
			(stroke
				(width 0.1)
				(type default)
			)
			(layer "B.Fab")
		)
		(fp_line
			(start 1.1049 -0.724916)
			(end 1.1049 0.724916)
			(stroke
				(width 0.1)
				(type default)
			)
			(layer "B.Fab")
		)
		(pad "1" smd rect
			(at 0.889 0 270)
			(size 1.016 1.27)
			(layers "B.Cu" "B.Mask" "B.Paste")
			(net "PVCCIN_CPU1")
		)
		(pad "2" smd rect
			(at -0.889 0 270)
			(size 1.016 1.27)
			(layers "B.Cu" "B.Mask" "B.Paste")
			(net "GND")
		)
	)
)
